(kicad_pcb
	(version 20260206)
	(generator "pcbnew")
	(generator_version "10.0")
	(general
		(thickness 1.6)
		(legacy_teardrops no)
	)
	(paper "A4")
	(title_block
		(title "04192023_DAF0TMB3IC0_F0TG_MB_C_brd_V02_OCP.brd")
		(comment 1 "Grand Teton / footprints 1971-1977 of 8354")
	)
	(layers
		(0 "F.Cu" signal "TOP")
		(4 "In1.Cu" signal "GND")
		(6 "In2.Cu" signal "IN1")
		(8 "In3.Cu" signal "GND1")
		(10 "In4.Cu" signal "IN2")
		(12 "In5.Cu" signal "GND2")
		(14 "In6.Cu" signal "IN3")
		(16 "In7.Cu" signal "GND3")
		(18 "In8.Cu" signal "VCC")
		(20 "In9.Cu" signal "VCC1")
		(22 "In10.Cu" signal "GND4")
		(24 "In11.Cu" signal "IN4")
		(26 "In12.Cu" signal "GND5")
		(28 "In13.Cu" signal "IN5")
		(30 "In14.Cu" signal "GND6")
		(32 "In15.Cu" signal "IN6")
		(34 "In16.Cu" signal "GND7")
		(2 "B.Cu" signal "BOTTOM")
		(9 "F.Adhes" user "F.Adhesive")
		(11 "B.Adhes" user "B.Adhesive")
		(13 "F.Paste" user "Package Geometry/Pastemask Top")
		(15 "B.Paste" user "Package Geometry/Pastemask Bottom")
		(5 "F.SilkS" user "Ref Des/Silkscreen Top")
		(7 "B.SilkS" user "Ref Des/Silkscreen Bottom")
		(1 "F.Mask" user "Board Geometry/Soldermask Top")
		(3 "B.Mask" user "Board Geometry/Soldermask Bottom")
		(17 "Dwgs.User" user "User.Drawings")
		(19 "Cmts.User" user "User.Comments")
		(21 "Eco1.User" user "User.Eco1")
		(23 "Eco2.User" user "User.Eco2")
		(25 "Edge.Cuts" user "Board Geometry/Outline")
		(27 "Margin" user)
		(31 "F.CrtYd" user "Package Geometry/Place Bound Top")
		(29 "B.CrtYd" user "Package Geometry/Place Bound Bottom")
		(35 "F.Fab" user "Ref Des/Assembly Top")
		(33 "B.Fab" user "Ref Des/Assembly Bottom")
	)
	(footprint ""
		(layer "F.Cu")
		(at 40.31996 -434.086 90)
		(property "Reference" "R2914"
			(at 0 0 90)
			(layer "F.SilkS")
			(hide yes)
			(effects
				(font
					(size 1.27 1.27)
				)
			)
		)
		(property "Value" ""
			(at 0 0 90)
			(layer "F.Fab")
			(effects
				(font
					(size 1.27 1.27)
				)
			)
		)
		(duplicate_pad_numbers_are_jumpers no)
		(fp_line
			(start 0.7874 -0.4064)
			(end 0.7874 0.4064)
			(stroke
				(width 0.1524)
				(type default)
			)
			(layer "F.SilkS")
		)
		(fp_line
			(start -0.7874 -0.4064)
			(end 0.7874 -0.4064)
			(stroke
				(width 0.1524)
				(type default)
			)
			(layer "F.SilkS")
		)
		(fp_line
			(start 0.7874 0.4064)
			(end -0.7874 0.4064)
			(stroke
				(width 0.1524)
				(type default)
			)
			(layer "F.SilkS")
		)
		(fp_line
			(start -0.7874 0.4064)
			(end -0.7874 -0.4064)
			(stroke
				(width 0.1524)
				(type default)
			)
			(layer "F.SilkS")
		)
		(fp_line
			(start -0.12065 -0.305054)
			(end -0.12065 -0.2794)
			(stroke
				(width 0.1)
				(type default)
			)
			(layer "F.Fab")
		)
		(fp_line
			(start -0.67945 -0.305054)
			(end -0.12065 -0.305054)
			(stroke
				(width 0.1)
				(type default)
			)
			(layer "F.Fab")
		)
		(fp_line
			(start 0.67945 -0.3048)
			(end 0.67945 0.3048)
			(stroke
				(width 0.1)
				(type default)
			)
			(layer "F.Fab")
		)
		(fp_line
			(start 0.12065 -0.3048)
			(end 0.67945 -0.3048)
			(stroke
				(width 0.1)
				(type default)
			)
			(layer "F.Fab")
		)
		(fp_line
			(start 0.12065 -0.2794)
			(end 0.12065 -0.3048)
			(stroke
				(width 0.1)
				(type default)
			)
			(layer "F.Fab")
		)
		(fp_line
			(start -0.12065 -0.2794)
			(end 0.12065 -0.2794)
			(stroke
				(width 0.1)
				(type default)
			)
			(layer "F.Fab")
		)
		(fp_line
			(start 0.120396 0.2794)
			(end -0.12065 0.2794)
			(stroke
				(width 0.1)
				(type default)
			)
			(layer "F.Fab")
		)
		(fp_line
			(start -0.12065 0.2794)
			(end -0.12065 0.3048)
			(stroke
				(width 0.1)
				(type default)
			)
			(layer "F.Fab")
		)
		(fp_line
			(start 0.67945 0.3048)
			(end 0.120396 0.3048)
			(stroke
				(width 0.1)
				(type default)
			)
			(layer "F.Fab")
		)
		(fp_line
			(start 0.120396 0.3048)
			(end 0.120396 0.2794)
			(stroke
				(width 0.1)
				(type default)
			)
			(layer "F.Fab")
		)
		(fp_line
			(start -0.12065 0.3048)
			(end -0.67945 0.3048)
			(stroke
				(width 0.1)
				(type default)
			)
			(layer "F.Fab")
		)
		(fp_line
			(start -0.67945 0.3048)
			(end -0.67945 -0.305054)
			(stroke
				(width 0.1)
				(type default)
			)
			(layer "F.Fab")
		)
		(pad "1" smd circle
			(at -0.40005 0 90)
			(size 0 0)
			(layers "F.Cu" "F.Mask" "F.Paste")
			(net "P3V3_AUX")
		)
		(pad "2" smd circle
			(at 0.40005 0 90)
			(size 0 0)
			(layers "F.Cu" "F.Mask" "F.Paste")
			(net "FM_SWB_PWR_EN_R1_BUF")
		)
	)
	(footprint ""
		(layer "F.Cu")
		(at 174.879 -137.632948 90)
		(property "Reference" "R248"
			(at 0 0 90)
			(layer "F.SilkS")
			(hide yes)
			(effects
				(font
					(size 1.27 1.27)
				)
			)
		)
		(property "Value" ""
			(at 0 0 90)
			(layer "F.Fab")
			(effects
				(font
					(size 1.27 1.27)
				)
			)
		)
		(duplicate_pad_numbers_are_jumpers no)
		(fp_line
			(start 0.7874 -0.4064)
			(end 0.7874 0.4064)
			(stroke
				(width 0.1524)
				(type default)
			)
			(layer "F.SilkS")
		)
		(fp_line
			(start -0.7874 -0.4064)
			(end 0.7874 -0.4064)
			(stroke
				(width 0.1524)
				(type default)
			)
			(layer "F.SilkS")
		)
		(fp_line
			(start 0.7874 0.4064)
			(end -0.7874 0.4064)
			(stroke
				(width 0.1524)
				(type default)
			)
			(layer "F.SilkS")
		)
		(fp_line
			(start -0.7874 0.4064)
			(end -0.7874 -0.4064)
			(stroke
				(width 0.1524)
				(type default)
			)
			(layer "F.SilkS")
		)
		(fp_line
			(start -0.12065 -0.305054)
			(end -0.12065 -0.2794)
			(stroke
				(width 0.1)
				(type default)
			)
			(layer "F.Fab")
		)
		(fp_line
			(start -0.67945 -0.305054)
			(end -0.12065 -0.305054)
			(stroke
				(width 0.1)
				(type default)
			)
			(layer "F.Fab")
		)
		(fp_line
			(start 0.67945 -0.3048)
			(end 0.67945 0.3048)
			(stroke
				(width 0.1)
				(type default)
			)
			(layer "F.Fab")
		)
		(fp_line
			(start 0.12065 -0.3048)
			(end 0.67945 -0.3048)
			(stroke
				(width 0.1)
				(type default)
			)
			(layer "F.Fab")
		)
		(fp_line
			(start 0.12065 -0.2794)
			(end 0.12065 -0.3048)
			(stroke
				(width 0.1)
				(type default)
			)
			(layer "F.Fab")
		)
		(fp_line
			(start -0.12065 -0.2794)
			(end 0.12065 -0.2794)
			(stroke
				(width 0.1)
				(type default)
			)
			(layer "F.Fab")
		)
		(fp_line
			(start 0.120396 0.2794)
			(end -0.12065 0.2794)
			(stroke
				(width 0.1)
				(type default)
			)
			(layer "F.Fab")
		)
		(fp_line
			(start -0.12065 0.2794)
			(end -0.12065 0.3048)
			(stroke
				(width 0.1)
				(type default)
			)
			(layer "F.Fab")
		)
		(fp_line
			(start 0.67945 0.3048)
			(end 0.120396 0.3048)
			(stroke
				(width 0.1)
				(type default)
			)
			(layer "F.Fab")
		)
		(fp_line
			(start 0.120396 0.3048)
			(end 0.120396 0.2794)
			(stroke
				(width 0.1)
				(type default)
			)
			(layer "F.Fab")
		)
		(fp_line
			(start -0.12065 0.3048)
			(end -0.67945 0.3048)
			(stroke
				(width 0.1)
				(type default)
			)
			(layer "F.Fab")
		)
		(fp_line
			(start -0.67945 0.3048)
			(end -0.67945 -0.305054)
			(stroke
				(width 0.1)
				(type default)
			)
			(layer "F.Fab")
		)
		(pad "1" smd circle
			(at -0.40005 0 90)
			(size 0 0)
			(layers "F.Cu" "F.Mask" "F.Paste")
			(net "FM_CPU0_SLP_S5_N")
		)
		(pad "2" smd circle
			(at 0.40005 0 90)
			(size 0 0)
			(layers "F.Cu" "F.Mask" "F.Paste")
			(net "CPU0_SLP_S5_N")
		)
	)
	(footprint ""
		(layer "F.Cu")
		(at 324.635876 -70.098412 90)
		(property "Reference" "D74"
			(at -3.934714 -0.691642 90)
			(unlocked yes)
			(layer "F.SilkS")
			(effects
				(font
					(size 0.7874 0.5842)
					(thickness 0.1524)
				)
				(justify left)
			)
		)
		(property "Value" ""
			(at 0 0 90)
			(layer "F.Fab")
			(effects
				(font
					(size 1.27 1.27)
				)
			)
		)
		(duplicate_pad_numbers_are_jumpers no)
		(fp_line
			(start 1.16078 -0.4826)
			(end 1.16078 0.4826)
			(stroke
				(width 0.1524)
				(type default)
			)
			(layer "F.SilkS")
		)
		(fp_line
			(start 1.03378 -0.4826)
			(end 1.03378 0.4826)
			(stroke
				(width 0.1524)
				(type default)
			)
			(layer "F.SilkS")
		)
		(fp_line
			(start 0.90678 -0.4826)
			(end 0.90678 0.4826)
			(stroke
				(width 0.1524)
				(type default)
			)
			(layer "F.SilkS")
		)
		(fp_line
			(start -0.64008 -0.4826)
			(end 1.16078 -0.4826)
			(stroke
				(width 0.1524)
				(type default)
			)
			(layer "F.SilkS")
		)
		(fp_line
			(start -0.79248 -0.4826)
			(end 1.03378 -0.4826)
			(stroke
				(width 0.1524)
				(type default)
			)
			(layer "F.SilkS")
		)
		(fp_line
			(start -0.89408 -0.4826)
			(end 0.90678 -0.4826)
			(stroke
				(width 0.1524)
				(type default)
			)
			(layer "F.SilkS")
		)
		(fp_line
			(start 1.16078 0.4826)
			(end -0.64008 0.4826)
			(stroke
				(width 0.1524)
				(type default)
			)
			(layer "F.SilkS")
		)
		(fp_line
			(start 1.03378 0.4826)
			(end -0.79248 0.4826)
			(stroke
				(width 0.1524)
				(type default)
			)
			(layer "F.SilkS")
		)
		(fp_line
			(start 0.90678 0.4826)
			(end -0.90678 0.4826)
			(stroke
				(width 0.1524)
				(type default)
			)
			(layer "F.SilkS")
		)
		(fp_line
			(start -0.90678 0.4826)
			(end -0.90678 -0.4699)
			(stroke
				(width 0.1524)
				(type default)
			)
			(layer "F.SilkS")
		)
		(fp_line
			(start 0.499872 -0.249936)
			(end 0.499872 0.249936)
			(stroke
				(width 0.1)
				(type default)
			)
			(layer "F.Fab")
		)
		(fp_line
			(start -0.499872 -0.249936)
			(end 0.499872 -0.249936)
			(stroke
				(width 0.1)
				(type default)
			)
			(layer "F.Fab")
		)
		(fp_line
			(start 0.499872 0.249936)
			(end -0.499872 0.249936)
			(stroke
				(width 0.1)
				(type default)
			)
			(layer "F.Fab")
		)
		(fp_line
			(start -0.499872 0.249936)
			(end -0.499872 -0.249936)
			(stroke
				(width 0.1)
				(type default)
			)
			(layer "F.Fab")
		)
		(pad "A" smd rect
			(at -0.47498 0 90)
			(size 0.6096 0.7112)
			(layers "F.Cu" "F.Mask" "F.Paste")
			(net "LED_PWRGD_PVDDCR_CPU0_P0_R")
		)
		(pad "C" smd rect
			(at 0.47498 0 90)
			(size 0.6096 0.7112)
			(layers "F.Cu" "F.Mask" "F.Paste")
			(net "LED_PWRGD_PVDDCR_CPU0_P0_D")
		)
	)
	(footprint ""
		(layer "F.Cu")
		(at 265.649964 -22.29993)
		(property "Reference" "H86"
			(at -4.919472 -5.971794 0)
			(unlocked yes)
			(layer "F.SilkS")
			(effects
				(font
					(size 0.7874 0.5842)
					(thickness 0.1524)
				)
				(justify left)
			)
		)
		(property "Value" ""
			(at 0 0 0)
			(layer "F.Fab")
			(effects
				(font
					(size 1.27 1.27)
				)
			)
		)
		(duplicate_pad_numbers_are_jumpers no)
		(pad "1" thru_hole circle
			(at 0 0)
			(size 10.0076 10.0076)
			(drill 5.6134)
			(layers "*.Cu" "*.Mask")
			(remove_unused_layers no)
			(net "GND")
			(clearance -1.9431)
		)
	)
	(footprint ""
		(layer "F.Cu")
		(at 105.64876 -57.486042 180)
		(property "Reference" "R1746"
			(at 0 0 180)
			(layer "F.SilkS")
			(hide yes)
			(effects
				(font
					(size 1.27 1.27)
				)
			)
		)
		(property "Value" ""
			(at 0 0 180)
			(layer "F.Fab")
			(effects
				(font
					(size 1.27 1.27)
				)
			)
		)
		(duplicate_pad_numbers_are_jumpers no)
		(fp_line
			(start 0.7874 0.4064)
			(end -0.7874 0.4064)
			(stroke
				(width 0.1524)
				(type default)
			)
			(layer "F.SilkS")
		)
		(fp_line
			(start 0.7874 -0.4064)
			(end 0.7874 0.4064)
			(stroke
				(width 0.1524)
				(type default)
			)
			(layer "F.SilkS")
		)
		(fp_line
			(start -0.7874 0.4064)
			(end -0.7874 -0.4064)
			(stroke
				(width 0.1524)
				(type default)
			)
			(layer "F.SilkS")
		)
		(fp_line
			(start -0.7874 -0.4064)
			(end 0.7874 -0.4064)
			(stroke
				(width 0.1524)
				(type default)
			)
			(layer "F.SilkS")
		)
		(fp_line
			(start 0.67945 0.3048)
			(end 0.120396 0.3048)
			(stroke
				(width 0.1)
				(type default)
			)
			(layer "F.Fab")
		)
		(fp_line
			(start 0.67945 -0.3048)
			(end 0.67945 0.3048)
			(stroke
				(width 0.1)
				(type default)
			)
			(layer "F.Fab")
		)
		(fp_line
			(start 0.12065 -0.2794)
			(end 0.12065 -0.3048)
			(stroke
				(width 0.1)
				(type default)
			)
			(layer "F.Fab")
		)
		(fp_line
			(start 0.12065 -0.3048)
			(end 0.67945 -0.3048)
			(stroke
				(width 0.1)
				(type default)
			)
			(layer "F.Fab")
		)
		(fp_line
			(start 0.120396 0.3048)
			(end 0.120396 0.2794)
			(stroke
				(width 0.1)
				(type default)
			)
			(layer "F.Fab")
		)
		(fp_line
			(start 0.120396 0.2794)
			(end -0.12065 0.2794)
			(stroke
				(width 0.1)
				(type default)
			)
			(layer "F.Fab")
		)
		(fp_line
			(start -0.12065 0.3048)
			(end -0.67945 0.3048)
			(stroke
				(width 0.1)
				(type default)
			)
			(layer "F.Fab")
		)
		(fp_line
			(start -0.12065 0.2794)
			(end -0.12065 0.3048)
			(stroke
				(width 0.1)
				(type default)
			)
			(layer "F.Fab")
		)
		(fp_line
			(start -0.12065 -0.2794)
			(end 0.12065 -0.2794)
			(stroke
				(width 0.1)
				(type default)
			)
			(layer "F.Fab")
		)
		(fp_line
			(start -0.12065 -0.305054)
			(end -0.12065 -0.2794)
			(stroke
				(width 0.1)
				(type default)
			)
			(layer "F.Fab")
		)
		(fp_line
			(start -0.67945 0.3048)
			(end -0.67945 -0.305054)
			(stroke
				(width 0.1)
				(type default)
			)
			(layer "F.Fab")
		)
		(fp_line
			(start -0.67945 -0.305054)
			(end -0.12065 -0.305054)
			(stroke
				(width 0.1)
				(type default)
			)
			(layer "F.Fab")
		)
		(pad "1" smd circle
			(at -0.40005 0 180)
			(size 0 0)
			(layers "F.Cu" "F.Mask" "F.Paste")
			(net "P3V3_AUX")
		)
		(pad "2" smd circle
			(at 0.40005 0 180)
			(size 0 0)
			(layers "F.Cu" "F.Mask" "F.Paste")
			(net "JTAG_SCM_MUX_TMS")
		)
	)
	(footprint ""
		(layer "F.Cu")
		(at 197.21068 -41.466516 180)
		(property "Reference" "R4062"
			(at 0 0 180)
			(layer "F.SilkS")
			(hide yes)
			(effects
				(font
					(size 1.27 1.27)
				)
			)
		)
		(property "Value" ""
			(at 0 0 180)
			(layer "F.Fab")
			(effects
				(font
					(size 1.27 1.27)
				)
			)
		)
		(duplicate_pad_numbers_are_jumpers no)
		(fp_line
			(start 0.7874 0.4064)
			(end -0.7874 0.4064)
			(stroke
				(width 0.1524)
				(type default)
			)
			(layer "F.SilkS")
		)
		(fp_line
			(start 0.7874 -0.4064)
			(end 0.7874 0.4064)
			(stroke
				(width 0.1524)
				(type default)
			)
			(layer "F.SilkS")
		)
		(fp_line
			(start -0.7874 0.4064)
			(end -0.7874 -0.4064)
			(stroke
				(width 0.1524)
				(type default)
			)
			(layer "F.SilkS")
		)
		(fp_line
			(start -0.7874 -0.4064)
			(end 0.7874 -0.4064)
			(stroke
				(width 0.1524)
				(type default)
			)
			(layer "F.SilkS")
		)
		(fp_line
			(start 0.67945 0.3048)
			(end 0.120396 0.3048)
			(stroke
				(width 0.1)
				(type default)
			)
			(layer "F.Fab")
		)
		(fp_line
			(start 0.67945 -0.3048)
			(end 0.67945 0.3048)
			(stroke
				(width 0.1)
				(type default)
			)
			(layer "F.Fab")
		)
		(fp_line
			(start 0.12065 -0.2794)
			(end 0.12065 -0.3048)
			(stroke
				(width 0.1)
				(type default)
			)
			(layer "F.Fab")
		)
		(fp_line
			(start 0.12065 -0.3048)
			(end 0.67945 -0.3048)
			(stroke
				(width 0.1)
				(type default)
			)
			(layer "F.Fab")
		)
		(fp_line
			(start 0.120396 0.3048)
			(end 0.120396 0.2794)
			(stroke
				(width 0.1)
				(type default)
			)
			(layer "F.Fab")
		)
		(fp_line
			(start 0.120396 0.2794)
			(end -0.12065 0.2794)
			(stroke
				(width 0.1)
				(type default)
			)
			(layer "F.Fab")
		)
		(fp_line
			(start -0.12065 0.3048)
			(end -0.67945 0.3048)
			(stroke
				(width 0.1)
				(type default)
			)
			(layer "F.Fab")
		)
		(fp_line
			(start -0.12065 0.2794)
			(end -0.12065 0.3048)
			(stroke
				(width 0.1)
				(type default)
			)
			(layer "F.Fab")
		)
		(fp_line
			(start -0.12065 -0.2794)
			(end 0.12065 -0.2794)
			(stroke
				(width 0.1)
				(type default)
			)
			(layer "F.Fab")
		)
		(fp_line
			(start -0.12065 -0.305054)
			(end -0.12065 -0.2794)
			(stroke
				(width 0.1)
				(type default)
			)
			(layer "F.Fab")
		)
		(fp_line
			(start -0.67945 0.3048)
			(end -0.67945 -0.305054)
			(stroke
				(width 0.1)
				(type default)
			)
			(layer "F.Fab")
		)
		(fp_line
			(start -0.67945 -0.305054)
			(end -0.12065 -0.305054)
			(stroke
				(width 0.1)
				(type default)
			)
			(layer "F.Fab")
		)
		(pad "1" smd circle
			(at -0.40005 0 180)
			(size 0 0)
			(layers "F.Cu" "F.Mask" "F.Paste")
			(net "P12V_SCM_EN")
		)
		(pad "2" smd circle
			(at 0.40005 0 180)
			(size 0 0)
			(layers "F.Cu" "F.Mask" "F.Paste")
			(net "P12V_SCM_EN_R")
		)
	)
	(footprint ""
		(layer "F.Cu")
		(at 103.190294 -384.10388 180)
		(property "Reference" "R704"
			(at 0 0 180)
			(layer "F.SilkS")
			(hide yes)
			(effects
				(font
					(size 1.27 1.27)
				)
			)
		)
		(property "Value" ""
			(at 0 0 180)
			(layer "F.Fab")
			(effects
				(font
					(size 1.27 1.27)
				)
			)
		)
		(duplicate_pad_numbers_are_jumpers no)
		(fp_line
			(start 0.7874 0.4064)
			(end -0.7874 0.4064)
			(stroke
				(width 0.1524)
				(type default)
			)
			(layer "F.SilkS")
		)
		(fp_line
			(start 0.7874 -0.4064)
			(end 0.7874 0.4064)
			(stroke
				(width 0.1524)
				(type default)
			)
			(layer "F.SilkS")
		)
		(fp_line
			(start -0.7874 0.4064)
			(end -0.7874 -0.4064)
			(stroke
				(width 0.1524)
				(type default)
			)
			(layer "F.SilkS")
		)
		(fp_line
			(start -0.7874 -0.4064)
			(end 0.7874 -0.4064)
			(stroke
				(width 0.1524)
				(type default)
			)
			(layer "F.SilkS")
		)
		(fp_line
			(start 0.67945 0.3048)
			(end 0.120396 0.3048)
			(stroke
				(width 0.1)
				(type default)
			)
			(layer "F.Fab")
		)
		(fp_line
			(start 0.67945 -0.3048)
			(end 0.67945 0.3048)
			(stroke
				(width 0.1)
				(type default)
			)
			(layer "F.Fab")
		)
		(fp_line
			(start 0.12065 -0.2794)
			(end 0.12065 -0.3048)
			(stroke
				(width 0.1)
				(type default)
			)
			(layer "F.Fab")
		)
		(fp_line
			(start 0.12065 -0.3048)
			(end 0.67945 -0.3048)
			(stroke
				(width 0.1)
				(type default)
			)
			(layer "F.Fab")
		)
		(fp_line
			(start 0.120396 0.3048)
			(end 0.120396 0.2794)
			(stroke
				(width 0.1)
				(type default)
			)
			(layer "F.Fab")
		)
		(fp_line
			(start 0.120396 0.2794)
			(end -0.12065 0.2794)
			(stroke
				(width 0.1)
				(type default)
			)
			(layer "F.Fab")
		)
		(fp_line
			(start -0.12065 0.3048)
			(end -0.67945 0.3048)
			(stroke
				(width 0.1)
				(type default)
			)
			(layer "F.Fab")
		)
		(fp_line
			(start -0.12065 0.2794)
			(end -0.12065 0.3048)
			(stroke
				(width 0.1)
				(type default)
			)
			(layer "F.Fab")
		)
		(fp_line
			(start -0.12065 -0.2794)
			(end 0.12065 -0.2794)
			(stroke
				(width 0.1)
				(type default)
			)
			(layer "F.Fab")
		)
		(fp_line
			(start -0.12065 -0.305054)
			(end -0.12065 -0.2794)
			(stroke
				(width 0.1)
				(type default)
			)
			(layer "F.Fab")
		)
		(fp_line
			(start -0.67945 0.3048)
			(end -0.67945 -0.305054)
			(stroke
				(width 0.1)
				(type default)
			)
			(layer "F.Fab")
		)
		(fp_line
			(start -0.67945 -0.305054)
			(end -0.12065 -0.305054)
			(stroke
				(width 0.1)
				(type default)
			)
			(layer "F.Fab")
		)
		(pad "1" smd rect
			(at -0.40005 0)
			(size 0.4572 0.508)
			(layers "F.Cu" "F.Mask" "F.Paste")
			(net "P1V8_CPU1_RT_1D")
		)
		(pad "2" smd rect
			(at 0.40005 0)
			(size 0.4572 0.508)
			(layers "F.Cu" "F.Mask" "F.Paste")
			(net "P1V8_CPU1_RT1_1A_1D")
		)
	)
)
